%#################################################################
Title:        Cref Error Report
Design:       scm
Date:         Mar 21 19:50:37 2022
%#################################################################



Warnings in Page : @scm_lib.scm(sch_1):Page13
Signal BMC_CPLD_GPIO_2 at (B 1) has too little display space.
Signal RST_BMC_SELF_HW at (B 1) has too little display space.

Warnings in Page : @scm_lib.scm(sch_1):Page24
Signal DP_BMC_HPD_3V3_BUF at (B 4) has too little display space.

Warnings in Page : @scm_lib.scm(sch_1):Page29
Signal USB3_01_MUX_FB_RXN at (A 4) has too little display space.

Warnings in Page : @scm_lib.scm(sch_1):Page52
Signal         EN_P3V3 at (B 2) has too little display space.
